# S9S_MB_2U (Grand Teton) — schematic netlist excerpt (pin names and nets, part order shuffled) for the footprints in the layout excerpt that follows; sources: Cadence DE-HDL packaged netlist, KiCad conversion of 03242023_DA0F0TMBIJ0_F0T_Motherboard_J_brd_V01_OCP.brd

C11  Q_CAP  2.2UF 6.3V 20% X6S  pkg C0402  page 85 : A = P3V3_AUX ; B = GND
R2735  Q_RES  33.2 1% CHIP  pkg 0402LF  page 114 : A = PWRGD_CHH_CPU0_DIMM2 ; B = PWRGD_FAIL_CPU0_GH

(kicad_pcb
	(version 20260206)
	(generator "pcbnew")
	(generator_version "10.0")
	(general
		(thickness 1.6)
		(legacy_teardrops no)
	)
	(paper "A4")
	(title_block
		(title "03242023_DA0F0TMBIJ0_F0T_Motherboard_J_brd_V01_OCP.brd")
		(comment 1 "Grand Teton / footprints 5449-5450 of 6105")
	)
	(layers
		(0 "F.Cu" signal "TOP")
		(4 "In1.Cu" signal "GND")
		(6 "In2.Cu" signal "IN1")
		(8 "In3.Cu" signal "GND1")
		(10 "In4.Cu" signal "IN2")
		(12 "In5.Cu" signal "GND2")
		(14 "In6.Cu" signal "IN3")
		(16 "In7.Cu" signal "GND3")
		(18 "In8.Cu" signal "VCC")
		(20 "In9.Cu" signal "VCC1")
		(22 "In10.Cu" signal "GND4")
		(24 "In11.Cu" signal "IN4")
		(26 "In12.Cu" signal "GND5")
		(28 "In13.Cu" signal "IN5")
		(30 "In14.Cu" signal "GND6")
		(32 "In15.Cu" signal "IN6")
		(34 "In16.Cu" signal "GND7")
		(2 "B.Cu" signal "BOTTOM")
		(9 "F.Adhes" user "F.Adhesive")
		(11 "B.Adhes" user "B.Adhesive")
		(13 "F.Paste" user "Package Geometry/Pastemask Top")
		(15 "B.Paste" user "Package Geometry/Pastemask Bottom")
		(5 "F.SilkS" user "Ref Des/Silkscreen Top")
		(7 "B.SilkS" user "Ref Des/Silkscreen Bottom")
		(1 "F.Mask" user "Board Geometry/Soldermask Top")
		(3 "B.Mask" user "Board Geometry/Soldermask Bottom")
		(17 "Dwgs.User" user "User.Drawings")
		(19 "Cmts.User" user "User.Comments")
		(21 "Eco1.User" user "User.Eco1")
		(23 "Eco2.User" user "User.Eco2")
		(25 "Edge.Cuts" user "Board Geometry/Outline")
		(27 "Margin" user)
		(31 "F.CrtYd" user "Package Geometry/Place Bound Top")
		(29 "B.CrtYd" user "Package Geometry/Place Bound Bottom")
		(35 "F.Fab" user "Ref Des/Assembly Top")
		(33 "B.Fab" user "Ref Des/Assembly Bottom")
	)
	(footprint ""
		(layer "B.Cu")
		(at 456.003406 -319.232026 180)
		(property "Reference" "R2735"
			(at 0 0 0)
			(layer "B.SilkS")
			(hide yes)
			(effects
				(font
					(size 1.27 1.27)
				)
				(justify mirror)
			)
		)
		(property "Value" ""
			(at 0 0 0)
			(layer "B.Fab")
			(effects
				(font
					(size 1.27 1.27)
				)
				(justify mirror)
			)
		)
		(duplicate_pad_numbers_are_jumpers no)
		(fp_line
			(start 0.7874 0.4064)
			(end 0.7874 -0.4064)
			(stroke
				(width 0.1524)
				(type default)
			)
			(layer "B.SilkS")
		)
		(fp_line
			(start 0.7874 -0.4064)
			(end -0.7874 -0.4064)
			(stroke
				(width 0.1524)
				(type default)
			)
			(layer "B.SilkS")
		)
		(fp_line
			(start -0.7874 0.4064)
			(end 0.7874 0.4064)
			(stroke
				(width 0.1524)
				(type default)
			)
			(layer "B.SilkS")
		)
		(fp_line
			(start -0.7874 -0.4064)
			(end -0.7874 0.4064)
			(stroke
				(width 0.1524)
				(type default)
			)
			(layer "B.SilkS")
		)
		(fp_line
			(start 0.67945 0.3048)
			(end 0.67945 -0.305054)
			(stroke
				(width 0.1)
				(type default)
			)
			(layer "B.Fab")
		)
		(fp_line
			(start 0.67945 -0.305054)
			(end 0.12065 -0.305054)
			(stroke
				(width 0.1)
				(type default)
			)
			(layer "B.Fab")
		)
		(fp_line
			(start 0.12065 0.3048)
			(end 0.67945 0.3048)
			(stroke
				(width 0.1)
				(type default)
			)
			(layer "B.Fab")
		)
		(fp_line
			(start 0.12065 0.2794)
			(end 0.12065 0.3048)
			(stroke
				(width 0.1)
				(type default)
			)
			(layer "B.Fab")
		)
		(fp_line
			(start 0.12065 -0.2794)
			(end -0.12065 -0.2794)
			(stroke
				(width 0.1)
				(type default)
			)
			(layer "B.Fab")
		)
		(fp_line
			(start 0.12065 -0.305054)
			(end 0.12065 -0.2794)
			(stroke
				(width 0.1)
				(type default)
			)
			(layer "B.Fab")
		)
		(fp_line
			(start -0.120396 0.3048)
			(end -0.120396 0.2794)
			(stroke
				(width 0.1)
				(type default)
			)
			(layer "B.Fab")
		)
		(fp_line
			(start -0.120396 0.2794)
			(end 0.12065 0.2794)
			(stroke
				(width 0.1)
				(type default)
			)
			(layer "B.Fab")
		)
		(fp_line
			(start -0.12065 -0.2794)
			(end -0.12065 -0.3048)
			(stroke
				(width 0.1)
				(type default)
			)
			(layer "B.Fab")
		)
		(fp_line
			(start -0.12065 -0.3048)
			(end -0.67945 -0.3048)
			(stroke
				(width 0.1)
				(type default)
			)
			(layer "B.Fab")
		)
		(fp_line
			(start -0.67945 0.3048)
			(end -0.120396 0.3048)
			(stroke
				(width 0.1)
				(type default)
			)
			(layer "B.Fab")
		)
		(fp_line
			(start -0.67945 -0.3048)
			(end -0.67945 0.3048)
			(stroke
				(width 0.1)
				(type default)
			)
			(layer "B.Fab")
		)
		(pad "1" smd circle
			(at 0.40005 0)
			(size 0 0)
			(layers "B.Cu" "B.Mask" "B.Paste")
			(net "PWRGD_CHH_CPU0_DIMM2")
		)
		(pad "2" smd circle
			(at -0.40005 0)
			(size 0 0)
			(layers "B.Cu" "B.Mask" "B.Paste")
			(net "PWRGD_FAIL_CPU0_GH")
		)
	)
	(footprint ""
		(layer "B.Cu")
		(at 293.812214 -319.263776 180)
		(property "Reference" "C11"
			(at 0 0 0)
			(layer "B.SilkS")
			(hide yes)
			(effects
				(font
					(size 1.27 1.27)
				)
				(justify mirror)
			)
		)
		(property "Value" ""
			(at 0 0 0)
			(layer "B.Fab")
			(effects
				(font
					(size 1.27 1.27)
				)
				(justify mirror)
			)
		)
		(duplicate_pad_numbers_are_jumpers no)
		(fp_line
			(start 0.7874 0.4064)
			(end 0.7874 -0.4064)
			(stroke
				(width 0.1524)
				(type default)
			)
			(layer "B.SilkS")
		)
		(fp_line
			(start 0.7874 -0.4064)
			(end -0.7874 -0.4064)
			(stroke
				(width 0.1524)
				(type default)
			)
			(layer "B.SilkS")
		)
		(fp_line
			(start -0.7874 0.4064)
			(end 0.7874 0.4064)
			(stroke
				(width 0.1524)
				(type default)
			)
			(layer "B.SilkS")
		)
		(fp_line
			(start -0.7874 -0.4064)
			(end -0.7874 0.4064)
			(stroke
				(width 0.1524)
				(type default)
			)
			(layer "B.SilkS")
		)
		(fp_line
			(start 0.67945 0.3048)
			(end 0.67945 -0.305054)
			(stroke
				(width 0.1)
				(type default)
			)
			(layer "B.Fab")
		)
		(fp_line
			(start 0.67945 -0.305054)
			(end 0.12065 -0.305054)
			(stroke
				(width 0.1)
				(type default)
			)
			(layer "B.Fab")
		)
		(fp_line
			(start 0.12065 0.3048)
			(end 0.67945 0.3048)
			(stroke
				(width 0.1)
				(type default)
			)
			(layer "B.Fab")
		)
		(fp_line
			(start 0.12065 0.2794)
			(end 0.12065 0.3048)
			(stroke
				(width 0.1)
				(type default)
			)
			(layer "B.Fab")
		)
		(fp_line
			(start 0.12065 -0.2794)
			(end -0.12065 -0.2794)
			(stroke
				(width 0.1)
				(type default)
			)
			(layer "B.Fab")
		)
		(fp_line
			(start 0.12065 -0.305054)
			(end 0.12065 -0.2794)
			(stroke
				(width 0.1)
				(type default)
			)
			(layer "B.Fab")
		)
		(fp_line
			(start -0.120396 0.3048)
			(end -0.120396 0.2794)
			(stroke
				(width 0.1)
				(type default)
			)
			(layer "B.Fab")
		)
		(fp_line
			(start -0.120396 0.2794)
			(end 0.12065 0.2794)
			(stroke
				(width 0.1)
				(type default)
			)
			(layer "B.Fab")
		)
		(fp_line
			(start -0.12065 -0.2794)
			(end -0.12065 -0.3048)
			(stroke
				(width 0.1)
				(type default)
			)
			(layer "B.Fab")
		)
		(fp_line
			(start -0.12065 -0.3048)
			(end -0.67945 -0.3048)
			(stroke
				(width 0.1)
				(type default)
			)
			(layer "B.Fab")
		)
		(fp_line
			(start -0.67945 0.3048)
			(end -0.120396 0.3048)
			(stroke
				(width 0.1)
				(type default)
			)
			(layer "B.Fab")
		)
		(fp_line
			(start -0.67945 -0.3048)
			(end -0.67945 0.3048)
			(stroke
				(width 0.1)
				(type default)
			)
			(layer "B.Fab")
		)
		(pad "1" smd circle
			(at 0.40005 0)
			(size 0 0)
			(layers "B.Cu" "B.Mask" "B.Paste")
			(net "P3V3_AUX")
		)
		(pad "2" smd circle
			(at -0.40005 0)
			(size 0 0)
			(layers "B.Cu" "B.Mask" "B.Paste")
			(net "GND")
		)
	)
)
